# S9S_MB_2U (Grand Teton) — schematic netlist excerpt (pin names and nets, part order shuffled) for the footprints in the layout excerpt that follows; sources: Cadence DE-HDL packaged netlist, KiCad conversion of 03242023_DA0F0TMBIJ0_F0T_Motherboard_J_brd_V01_OCP.brd

R4783  Q_RES  33.2 1% EMPTY  pkg 0402LF  page 307 : A = IRQ_UV_DETECT_R2_N ; B = IRQ_UV_DETECT_N
PC1364  Q_CAP  0.1UF 25V 10% X7R  pkg 0402  page 293 : A = GND ; B = PVCCINFAON_CPU1_VREF

(kicad_pcb
	(version 20260206)
	(generator "pcbnew")
	(generator_version "10.0")
	(general
		(thickness 1.6)
		(legacy_teardrops no)
	)
	(paper "A4")
	(title_block
		(title "03242023_DA0F0TMBIJ0_F0T_Motherboard_J_brd_V01_OCP.brd")
		(comment 1 "Grand Teton / footprints 1588-1589 of 6105")
	)
	(layers
		(0 "F.Cu" signal "TOP")
		(4 "In1.Cu" signal "GND")
		(6 "In2.Cu" signal "IN1")
		(8 "In3.Cu" signal "GND1")
		(10 "In4.Cu" signal "IN2")
		(12 "In5.Cu" signal "GND2")
		(14 "In6.Cu" signal "IN3")
		(16 "In7.Cu" signal "GND3")
		(18 "In8.Cu" signal "VCC")
		(20 "In9.Cu" signal "VCC1")
		(22 "In10.Cu" signal "GND4")
		(24 "In11.Cu" signal "IN4")
		(26 "In12.Cu" signal "GND5")
		(28 "In13.Cu" signal "IN5")
		(30 "In14.Cu" signal "GND6")
		(32 "In15.Cu" signal "IN6")
		(34 "In16.Cu" signal "GND7")
		(2 "B.Cu" signal "BOTTOM")
		(9 "F.Adhes" user "F.Adhesive")
		(11 "B.Adhes" user "B.Adhesive")
		(13 "F.Paste" user "Package Geometry/Pastemask Top")
		(15 "B.Paste" user "Package Geometry/Pastemask Bottom")
		(5 "F.SilkS" user "Ref Des/Silkscreen Top")
		(7 "B.SilkS" user "Ref Des/Silkscreen Bottom")
		(1 "F.Mask" user "Board Geometry/Soldermask Top")
		(3 "B.Mask" user "Board Geometry/Soldermask Bottom")
		(17 "Dwgs.User" user "User.Drawings")
		(19 "Cmts.User" user "User.Comments")
		(21 "Eco1.User" user "User.Eco1")
		(23 "Eco2.User" user "User.Eco2")
		(25 "Edge.Cuts" user "Board Geometry/Outline")
		(27 "Margin" user)
		(31 "F.CrtYd" user "Package Geometry/Place Bound Top")
		(29 "B.CrtYd" user "Package Geometry/Place Bound Bottom")
		(35 "F.Fab" user "Ref Des/Assembly Top")
		(33 "B.Fab" user "Ref Des/Assembly Bottom")
	)
	(footprint ""
		(layer "F.Cu")
		(at 50.317654 -153.644854)
		(property "Reference" "PC1364"
			(at 0 0 0)
			(layer "F.SilkS")
			(hide yes)
			(effects
				(font
					(size 1.27 1.27)
				)
			)
		)
		(property "Value" ""
			(at 0 0 0)
			(layer "F.Fab")
			(effects
				(font
					(size 1.27 1.27)
				)
			)
		)
		(duplicate_pad_numbers_are_jumpers no)
		(fp_line
			(start -0.7874 -0.4064)
			(end 0.7874 -0.4064)
			(stroke
				(width 0.1524)
				(type default)
			)
			(layer "F.SilkS")
		)
		(fp_line
			(start -0.7874 0.4064)
			(end -0.7874 -0.4064)
			(stroke
				(width 0.1524)
				(type default)
			)
			(layer "F.SilkS")
		)
		(fp_line
			(start 0.7874 -0.4064)
			(end 0.7874 0.4064)
			(stroke
				(width 0.1524)
				(type default)
			)
			(layer "F.SilkS")
		)
		(fp_line
			(start 0.7874 0.4064)
			(end -0.7874 0.4064)
			(stroke
				(width 0.1524)
				(type default)
			)
			(layer "F.SilkS")
		)
		(fp_line
			(start -0.67945 -0.305054)
			(end -0.12065 -0.305054)
			(stroke
				(width 0.1)
				(type default)
			)
			(layer "F.Fab")
		)
		(fp_line
			(start -0.67945 0.3048)
			(end -0.67945 -0.305054)
			(stroke
				(width 0.1)
				(type default)
			)
			(layer "F.Fab")
		)
		(fp_line
			(start -0.12065 -0.305054)
			(end -0.12065 -0.2794)
			(stroke
				(width 0.1)
				(type default)
			)
			(layer "F.Fab")
		)
		(fp_line
			(start -0.12065 -0.2794)
			(end 0.12065 -0.2794)
			(stroke
				(width 0.1)
				(type default)
			)
			(layer "F.Fab")
		)
		(fp_line
			(start -0.12065 0.2794)
			(end -0.12065 0.3048)
			(stroke
				(width 0.1)
				(type default)
			)
			(layer "F.Fab")
		)
		(fp_line
			(start -0.12065 0.3048)
			(end -0.67945 0.3048)
			(stroke
				(width 0.1)
				(type default)
			)
			(layer "F.Fab")
		)
		(fp_line
			(start 0.120396 0.2794)
			(end -0.12065 0.2794)
			(stroke
				(width 0.1)
				(type default)
			)
			(layer "F.Fab")
		)
		(fp_line
			(start 0.120396 0.3048)
			(end 0.120396 0.2794)
			(stroke
				(width 0.1)
				(type default)
			)
			(layer "F.Fab")
		)
		(fp_line
			(start 0.12065 -0.3048)
			(end 0.67945 -0.3048)
			(stroke
				(width 0.1)
				(type default)
			)
			(layer "F.Fab")
		)
		(fp_line
			(start 0.12065 -0.2794)
			(end 0.12065 -0.3048)
			(stroke
				(width 0.1)
				(type default)
			)
			(layer "F.Fab")
		)
		(fp_line
			(start 0.67945 -0.3048)
			(end 0.67945 0.3048)
			(stroke
				(width 0.1)
				(type default)
			)
			(layer "F.Fab")
		)
		(fp_line
			(start 0.67945 0.3048)
			(end 0.120396 0.3048)
			(stroke
				(width 0.1)
				(type default)
			)
			(layer "F.Fab")
		)
		(pad "1" smd circle
			(at -0.40005 0)
			(size 0 0)
			(layers "F.Cu" "F.Mask" "F.Paste")
			(net "GND")
		)
		(pad "2" smd circle
			(at 0.40005 0)
			(size 0 0)
			(layers "F.Cu" "F.Mask" "F.Paste")
			(net "PVCCINFAON_CPU1_VREF")
		)
	)
	(footprint ""
		(layer "F.Cu")
		(at 210.3882 -107.4166 -90)
		(property "Reference" "R4783"
			(at 0 0 270)
			(layer "F.SilkS")
			(hide yes)
			(effects
				(font
					(size 1.27 1.27)
				)
			)
		)
		(property "Value" ""
			(at 0 0 270)
			(layer "F.Fab")
			(effects
				(font
					(size 1.27 1.27)
				)
			)
		)
		(duplicate_pad_numbers_are_jumpers no)
		(fp_line
			(start -0.7874 0.4064)
			(end -0.7874 -0.4064)
			(stroke
				(width 0.1524)
				(type default)
			)
			(layer "F.SilkS")
		)
		(fp_line
			(start 0.7874 0.4064)
			(end -0.7874 0.4064)
			(stroke
				(width 0.1524)
				(type default)
			)
			(layer "F.SilkS")
		)
		(fp_line
			(start -0.7874 -0.4064)
			(end 0.7874 -0.4064)
			(stroke
				(width 0.1524)
				(type default)
			)
			(layer "F.SilkS")
		)
		(fp_line
			(start 0.7874 -0.4064)
			(end 0.7874 0.4064)
			(stroke
				(width 0.1524)
				(type default)
			)
			(layer "F.SilkS")
		)
		(fp_line
			(start -0.67945 0.3048)
			(end -0.67945 -0.305054)
			(stroke
				(width 0.1)
				(type default)
			)
			(layer "F.Fab")
		)
		(fp_line
			(start -0.12065 0.3048)
			(end -0.67945 0.3048)
			(stroke
				(width 0.1)
				(type default)
			)
			(layer "F.Fab")
		)
		(fp_line
			(start 0.120396 0.3048)
			(end 0.120396 0.2794)
			(stroke
				(width 0.1)
				(type default)
			)
			(layer "F.Fab")
		)
		(fp_line
			(start 0.67945 0.3048)
			(end 0.120396 0.3048)
			(stroke
				(width 0.1)
				(type default)
			)
			(layer "F.Fab")
		)
		(fp_line
			(start -0.12065 0.2794)
			(end -0.12065 0.3048)
			(stroke
				(width 0.1)
				(type default)
			)
			(layer "F.Fab")
		)
		(fp_line
			(start 0.120396 0.2794)
			(end -0.12065 0.2794)
			(stroke
				(width 0.1)
				(type default)
			)
			(layer "F.Fab")
		)
		(fp_line
			(start -0.12065 -0.2794)
			(end 0.12065 -0.2794)
			(stroke
				(width 0.1)
				(type default)
			)
			(layer "F.Fab")
		)
		(fp_line
			(start 0.12065 -0.2794)
			(end 0.12065 -0.3048)
			(stroke
				(width 0.1)
				(type default)
			)
			(layer "F.Fab")
		)
		(fp_line
			(start 0.12065 -0.3048)
			(end 0.67945 -0.3048)
			(stroke
				(width 0.1)
				(type default)
			)
			(layer "F.Fab")
		)
		(fp_line
			(start 0.67945 -0.3048)
			(end 0.67945 0.3048)
			(stroke
				(width 0.1)
				(type default)
			)
			(layer "F.Fab")
		)
		(fp_line
			(start -0.67945 -0.305054)
			(end -0.12065 -0.305054)
			(stroke
				(width 0.1)
				(type default)
			)
			(layer "F.Fab")
		)
		(fp_line
			(start -0.12065 -0.305054)
			(end -0.12065 -0.2794)
			(stroke
				(width 0.1)
				(type default)
			)
			(layer "F.Fab")
		)
		(pad "1" smd circle
			(at -0.40005 0 270)
			(size 0 0)
			(layers "F.Cu" "F.Mask" "F.Paste")
			(net "IRQ_UV_DETECT_R2_N")
		)
		(pad "2" smd circle
			(at 0.40005 0 270)
			(size 0 0)
			(layers "F.Cu" "F.Mask" "F.Paste")
			(net "IRQ_UV_DETECT_N")
		)
	)
)
